# S9S_MB_2U (Grand Teton) — schematic netlist excerpt (pin names and nets, part order shuffled) for the footprints in the layout excerpt that follows; sources: Cadence DE-HDL packaged netlist, KiCad conversion of 03242023_DA0F0TMBIJ0_F0T_Motherboard_J_brd_V01_OCP.brd

R4686  Q_RES  10.5K 1% EMPTY  pkg 0402LF  page 305 : A = P3V3_AUX ; B = P12V_HSC_T_CRIT_R_N
R1758  Q_RES  33.2 1% CHIP  pkg 0402LF  page 222 : A = SGPIO_LD_1 ; B = SGPIO_BMC_LD_N

(kicad_pcb
	(version 20260206)
	(generator "pcbnew")
	(generator_version "10.0")
	(general
		(thickness 1.6)
		(legacy_teardrops no)
	)
	(paper "A4")
	(title_block
		(title "03242023_DA0F0TMBIJ0_F0T_Motherboard_J_brd_V01_OCP.brd")
		(comment 1 "Grand Teton / footprints 4089-4090 of 6105")
	)
	(layers
		(0 "F.Cu" signal "TOP")
		(4 "In1.Cu" signal "GND")
		(6 "In2.Cu" signal "IN1")
		(8 "In3.Cu" signal "GND1")
		(10 "In4.Cu" signal "IN2")
		(12 "In5.Cu" signal "GND2")
		(14 "In6.Cu" signal "IN3")
		(16 "In7.Cu" signal "GND3")
		(18 "In8.Cu" signal "VCC")
		(20 "In9.Cu" signal "VCC1")
		(22 "In10.Cu" signal "GND4")
		(24 "In11.Cu" signal "IN4")
		(26 "In12.Cu" signal "GND5")
		(28 "In13.Cu" signal "IN5")
		(30 "In14.Cu" signal "GND6")
		(32 "In15.Cu" signal "IN6")
		(34 "In16.Cu" signal "GND7")
		(2 "B.Cu" signal "BOTTOM")
		(9 "F.Adhes" user "F.Adhesive")
		(11 "B.Adhes" user "B.Adhesive")
		(13 "F.Paste" user "Package Geometry/Pastemask Top")
		(15 "B.Paste" user "Package Geometry/Pastemask Bottom")
		(5 "F.SilkS" user "Ref Des/Silkscreen Top")
		(7 "B.SilkS" user "Ref Des/Silkscreen Bottom")
		(1 "F.Mask" user "Board Geometry/Soldermask Top")
		(3 "B.Mask" user "Board Geometry/Soldermask Bottom")
		(17 "Dwgs.User" user "User.Drawings")
		(19 "Cmts.User" user "User.Comments")
		(21 "Eco1.User" user "User.Eco1")
		(23 "Eco2.User" user "User.Eco2")
		(25 "Edge.Cuts" user "Board Geometry/Outline")
		(27 "Margin" user)
		(31 "F.CrtYd" user "Package Geometry/Place Bound Top")
		(29 "B.CrtYd" user "Package Geometry/Place Bound Bottom")
		(35 "F.Fab" user "Ref Des/Assembly Top")
		(33 "B.Fab" user "Ref Des/Assembly Bottom")
	)
	(footprint ""
		(layer "F.Cu")
		(at 288.9377 -405.79802 180)
		(property "Reference" "R4686"
			(at 0 0 180)
			(layer "F.SilkS")
			(hide yes)
			(effects
				(font
					(size 1.27 1.27)
				)
			)
		)
		(property "Value" ""
			(at 0 0 180)
			(layer "F.Fab")
			(effects
				(font
					(size 1.27 1.27)
				)
			)
		)
		(duplicate_pad_numbers_are_jumpers no)
		(fp_line
			(start 0.7874 0.4064)
			(end -0.7874 0.4064)
			(stroke
				(width 0.1524)
				(type default)
			)
			(layer "F.SilkS")
		)
		(fp_line
			(start 0.7874 -0.4064)
			(end 0.7874 0.4064)
			(stroke
				(width 0.1524)
				(type default)
			)
			(layer "F.SilkS")
		)
		(fp_line
			(start -0.7874 0.4064)
			(end -0.7874 -0.4064)
			(stroke
				(width 0.1524)
				(type default)
			)
			(layer "F.SilkS")
		)
		(fp_line
			(start -0.7874 -0.4064)
			(end 0.7874 -0.4064)
			(stroke
				(width 0.1524)
				(type default)
			)
			(layer "F.SilkS")
		)
		(fp_line
			(start 0.67945 0.3048)
			(end 0.120396 0.3048)
			(stroke
				(width 0.1)
				(type default)
			)
			(layer "F.Fab")
		)
		(fp_line
			(start 0.67945 -0.3048)
			(end 0.67945 0.3048)
			(stroke
				(width 0.1)
				(type default)
			)
			(layer "F.Fab")
		)
		(fp_line
			(start 0.12065 -0.2794)
			(end 0.12065 -0.3048)
			(stroke
				(width 0.1)
				(type default)
			)
			(layer "F.Fab")
		)
		(fp_line
			(start 0.12065 -0.3048)
			(end 0.67945 -0.3048)
			(stroke
				(width 0.1)
				(type default)
			)
			(layer "F.Fab")
		)
		(fp_line
			(start 0.120396 0.3048)
			(end 0.120396 0.2794)
			(stroke
				(width 0.1)
				(type default)
			)
			(layer "F.Fab")
		)
		(fp_line
			(start 0.120396 0.2794)
			(end -0.12065 0.2794)
			(stroke
				(width 0.1)
				(type default)
			)
			(layer "F.Fab")
		)
		(fp_line
			(start -0.12065 0.3048)
			(end -0.67945 0.3048)
			(stroke
				(width 0.1)
				(type default)
			)
			(layer "F.Fab")
		)
		(fp_line
			(start -0.12065 0.2794)
			(end -0.12065 0.3048)
			(stroke
				(width 0.1)
				(type default)
			)
			(layer "F.Fab")
		)
		(fp_line
			(start -0.12065 -0.2794)
			(end 0.12065 -0.2794)
			(stroke
				(width 0.1)
				(type default)
			)
			(layer "F.Fab")
		)
		(fp_line
			(start -0.12065 -0.305054)
			(end -0.12065 -0.2794)
			(stroke
				(width 0.1)
				(type default)
			)
			(layer "F.Fab")
		)
		(fp_line
			(start -0.67945 0.3048)
			(end -0.67945 -0.305054)
			(stroke
				(width 0.1)
				(type default)
			)
			(layer "F.Fab")
		)
		(fp_line
			(start -0.67945 -0.305054)
			(end -0.12065 -0.305054)
			(stroke
				(width 0.1)
				(type default)
			)
			(layer "F.Fab")
		)
		(pad "1" smd circle
			(at -0.40005 0 180)
			(size 0 0)
			(layers "F.Cu" "F.Mask" "F.Paste")
			(net "P3V3_AUX")
		)
		(pad "2" smd circle
			(at 0.40005 0 180)
			(size 0 0)
			(layers "F.Cu" "F.Mask" "F.Paste")
			(net "P12V_HSC_T_CRIT_R_N")
		)
	)
	(footprint ""
		(layer "F.Cu")
		(at 164.465 -99.786948)
		(property "Reference" "R1758"
			(at 0 0 0)
			(layer "F.SilkS")
			(hide yes)
			(effects
				(font
					(size 1.27 1.27)
				)
			)
		)
		(property "Value" ""
			(at 0 0 0)
			(layer "F.Fab")
			(effects
				(font
					(size 1.27 1.27)
				)
			)
		)
		(duplicate_pad_numbers_are_jumpers no)
		(fp_line
			(start -0.7874 -0.4064)
			(end 0.7874 -0.4064)
			(stroke
				(width 0.1524)
				(type default)
			)
			(layer "F.SilkS")
		)
		(fp_line
			(start -0.7874 0.4064)
			(end -0.7874 -0.4064)
			(stroke
				(width 0.1524)
				(type default)
			)
			(layer "F.SilkS")
		)
		(fp_line
			(start 0.7874 -0.4064)
			(end 0.7874 0.4064)
			(stroke
				(width 0.1524)
				(type default)
			)
			(layer "F.SilkS")
		)
		(fp_line
			(start 0.7874 0.4064)
			(end -0.7874 0.4064)
			(stroke
				(width 0.1524)
				(type default)
			)
			(layer "F.SilkS")
		)
		(fp_line
			(start -0.67945 -0.305054)
			(end -0.12065 -0.305054)
			(stroke
				(width 0.1)
				(type default)
			)
			(layer "F.Fab")
		)
		(fp_line
			(start -0.67945 0.3048)
			(end -0.67945 -0.305054)
			(stroke
				(width 0.1)
				(type default)
			)
			(layer "F.Fab")
		)
		(fp_line
			(start -0.12065 -0.305054)
			(end -0.12065 -0.2794)
			(stroke
				(width 0.1)
				(type default)
			)
			(layer "F.Fab")
		)
		(fp_line
			(start -0.12065 -0.2794)
			(end 0.12065 -0.2794)
			(stroke
				(width 0.1)
				(type default)
			)
			(layer "F.Fab")
		)
		(fp_line
			(start -0.12065 0.2794)
			(end -0.12065 0.3048)
			(stroke
				(width 0.1)
				(type default)
			)
			(layer "F.Fab")
		)
		(fp_line
			(start -0.12065 0.3048)
			(end -0.67945 0.3048)
			(stroke
				(width 0.1)
				(type default)
			)
			(layer "F.Fab")
		)
		(fp_line
			(start 0.120396 0.2794)
			(end -0.12065 0.2794)
			(stroke
				(width 0.1)
				(type default)
			)
			(layer "F.Fab")
		)
		(fp_line
			(start 0.120396 0.3048)
			(end 0.120396 0.2794)
			(stroke
				(width 0.1)
				(type default)
			)
			(layer "F.Fab")
		)
		(fp_line
			(start 0.12065 -0.3048)
			(end 0.67945 -0.3048)
			(stroke
				(width 0.1)
				(type default)
			)
			(layer "F.Fab")
		)
		(fp_line
			(start 0.12065 -0.2794)
			(end 0.12065 -0.3048)
			(stroke
				(width 0.1)
				(type default)
			)
			(layer "F.Fab")
		)
		(fp_line
			(start 0.67945 -0.3048)
			(end 0.67945 0.3048)
			(stroke
				(width 0.1)
				(type default)
			)
			(layer "F.Fab")
		)
		(fp_line
			(start 0.67945 0.3048)
			(end 0.120396 0.3048)
			(stroke
				(width 0.1)
				(type default)
			)
			(layer "F.Fab")
		)
		(pad "1" smd circle
			(at -0.40005 0)
			(size 0 0)
			(layers "F.Cu" "F.Mask" "F.Paste")
			(net "SGPIO_LD_1")
		)
		(pad "2" smd circle
			(at 0.40005 0)
			(size 0 0)
			(layers "F.Cu" "F.Mask" "F.Paste")
			(net "SGPIO_BMC_LD_N")
		)
	)
)
